# S9S_MB_2U (Grand Teton) — schematic netlist excerpt (pin names and nets, part order shuffled) for the footprints in the layout excerpt that follows; sources: Cadence DE-HDL packaged netlist, KiCad conversion of 03242023_DA0F0TMBIJ0_F0T_Motherboard_J_brd_V01_OCP.brd

PC631  Q_CAP  470PF 50V 10% X7R  pkg 0402  page 278 : A = PVCCD_HV_CPU0_ATSEN ; B = GND
PL65  Q_INDUCTOR  4.7UH IND  pkg SMLF  page 258 : \1\ = SW_P5V_AUX_SW ; \2\ = P5V_AUX

(kicad_pcb
	(version 20260206)
	(generator "pcbnew")
	(generator_version "10.0")
	(general
		(thickness 1.6)
		(legacy_teardrops no)
	)
	(paper "A4")
	(title_block
		(title "03242023_DA0F0TMBIJ0_F0T_Motherboard_J_brd_V01_OCP.brd")
		(comment 1 "Grand Teton / footprints 3817-3818 of 6105")
	)
	(layers
		(0 "F.Cu" signal "TOP")
		(4 "In1.Cu" signal "GND")
		(6 "In2.Cu" signal "IN1")
		(8 "In3.Cu" signal "GND1")
		(10 "In4.Cu" signal "IN2")
		(12 "In5.Cu" signal "GND2")
		(14 "In6.Cu" signal "IN3")
		(16 "In7.Cu" signal "GND3")
		(18 "In8.Cu" signal "VCC")
		(20 "In9.Cu" signal "VCC1")
		(22 "In10.Cu" signal "GND4")
		(24 "In11.Cu" signal "IN4")
		(26 "In12.Cu" signal "GND5")
		(28 "In13.Cu" signal "IN5")
		(30 "In14.Cu" signal "GND6")
		(32 "In15.Cu" signal "IN6")
		(34 "In16.Cu" signal "GND7")
		(2 "B.Cu" signal "BOTTOM")
		(9 "F.Adhes" user "F.Adhesive")
		(11 "B.Adhes" user "B.Adhesive")
		(13 "F.Paste" user "Package Geometry/Pastemask Top")
		(15 "B.Paste" user "Package Geometry/Pastemask Bottom")
		(5 "F.SilkS" user "Ref Des/Silkscreen Top")
		(7 "B.SilkS" user "Ref Des/Silkscreen Bottom")
		(1 "F.Mask" user "Board Geometry/Soldermask Top")
		(3 "B.Mask" user "Board Geometry/Soldermask Bottom")
		(17 "Dwgs.User" user "User.Drawings")
		(19 "Cmts.User" user "User.Comments")
		(21 "Eco1.User" user "User.Eco1")
		(23 "Eco2.User" user "User.Eco2")
		(25 "Edge.Cuts" user "Board Geometry/Outline")
		(27 "Margin" user)
		(31 "F.CrtYd" user "Package Geometry/Place Bound Top")
		(29 "B.CrtYd" user "Package Geometry/Place Bound Bottom")
		(35 "F.Fab" user "Ref Des/Assembly Top")
		(33 "B.Fab" user "Ref Des/Assembly Bottom")
	)
	(footprint ""
		(layer "F.Cu")
		(at 428.226474 -124.02566 180)
		(property "Reference" "PC631"
			(at 0 0 180)
			(layer "F.SilkS")
			(hide yes)
			(effects
				(font
					(size 1.27 1.27)
				)
			)
		)
		(property "Value" ""
			(at 0 0 180)
			(layer "F.Fab")
			(effects
				(font
					(size 1.27 1.27)
				)
			)
		)
		(duplicate_pad_numbers_are_jumpers no)
		(fp_line
			(start 0.7874 0.4064)
			(end -0.7874 0.4064)
			(stroke
				(width 0.1524)
				(type default)
			)
			(layer "F.SilkS")
		)
		(fp_line
			(start 0.7874 -0.4064)
			(end 0.7874 0.4064)
			(stroke
				(width 0.1524)
				(type default)
			)
			(layer "F.SilkS")
		)
		(fp_line
			(start -0.7874 0.4064)
			(end -0.7874 -0.4064)
			(stroke
				(width 0.1524)
				(type default)
			)
			(layer "F.SilkS")
		)
		(fp_line
			(start -0.7874 -0.4064)
			(end 0.7874 -0.4064)
			(stroke
				(width 0.1524)
				(type default)
			)
			(layer "F.SilkS")
		)
		(fp_line
			(start 0.67945 0.3048)
			(end 0.120396 0.3048)
			(stroke
				(width 0.1)
				(type default)
			)
			(layer "F.Fab")
		)
		(fp_line
			(start 0.67945 -0.3048)
			(end 0.67945 0.3048)
			(stroke
				(width 0.1)
				(type default)
			)
			(layer "F.Fab")
		)
		(fp_line
			(start 0.12065 -0.2794)
			(end 0.12065 -0.3048)
			(stroke
				(width 0.1)
				(type default)
			)
			(layer "F.Fab")
		)
		(fp_line
			(start 0.12065 -0.3048)
			(end 0.67945 -0.3048)
			(stroke
				(width 0.1)
				(type default)
			)
			(layer "F.Fab")
		)
		(fp_line
			(start 0.120396 0.3048)
			(end 0.120396 0.2794)
			(stroke
				(width 0.1)
				(type default)
			)
			(layer "F.Fab")
		)
		(fp_line
			(start 0.120396 0.2794)
			(end -0.12065 0.2794)
			(stroke
				(width 0.1)
				(type default)
			)
			(layer "F.Fab")
		)
		(fp_line
			(start -0.12065 0.3048)
			(end -0.67945 0.3048)
			(stroke
				(width 0.1)
				(type default)
			)
			(layer "F.Fab")
		)
		(fp_line
			(start -0.12065 0.2794)
			(end -0.12065 0.3048)
			(stroke
				(width 0.1)
				(type default)
			)
			(layer "F.Fab")
		)
		(fp_line
			(start -0.12065 -0.2794)
			(end 0.12065 -0.2794)
			(stroke
				(width 0.1)
				(type default)
			)
			(layer "F.Fab")
		)
		(fp_line
			(start -0.12065 -0.305054)
			(end -0.12065 -0.2794)
			(stroke
				(width 0.1)
				(type default)
			)
			(layer "F.Fab")
		)
		(fp_line
			(start -0.67945 0.3048)
			(end -0.67945 -0.305054)
			(stroke
				(width 0.1)
				(type default)
			)
			(layer "F.Fab")
		)
		(fp_line
			(start -0.67945 -0.305054)
			(end -0.12065 -0.305054)
			(stroke
				(width 0.1)
				(type default)
			)
			(layer "F.Fab")
		)
		(pad "1" smd circle
			(at -0.40005 0 180)
			(size 0 0)
			(layers "F.Cu" "F.Mask" "F.Paste")
			(net "PVCCD_HV_CPU0_ATSEN")
		)
		(pad "2" smd circle
			(at 0.40005 0 180)
			(size 0 0)
			(layers "F.Cu" "F.Mask" "F.Paste")
			(net "GND")
		)
	)
	(footprint ""
		(layer "F.Cu")
		(at 447.771774 -385.117594 180)
		(property "Reference" "PL65"
			(at -2.455926 5.957824 0)
			(unlocked yes)
			(layer "F.SilkS")
			(effects
				(font
					(size 0.7874 0.5842)
					(thickness 0.1524)
				)
				(justify left)
			)
		)
		(property "Value" ""
			(at 0 0 180)
			(layer "F.Fab")
			(effects
				(font
					(size 1.27 1.27)
				)
			)
		)
		(duplicate_pad_numbers_are_jumpers no)
		(fp_line
			(start 5.588 5.150104)
			(end 5.588 1.8034)
			(stroke
				(width 0.1524)
				(type default)
			)
			(layer "F.SilkS")
		)
		(fp_line
			(start 5.588 -1.8288)
			(end 5.588 -5.150104)
			(stroke
				(width 0.1524)
				(type default)
			)
			(layer "F.SilkS")
		)
		(fp_line
			(start 5.588 -5.150104)
			(end -5.588 -5.150104)
			(stroke
				(width 0.1524)
				(type default)
			)
			(layer "F.SilkS")
		)
		(fp_line
			(start -5.588 5.150104)
			(end 5.588 5.150104)
			(stroke
				(width 0.1524)
				(type default)
			)
			(layer "F.SilkS")
		)
		(fp_line
			(start -5.588 1.8288)
			(end -5.588 5.150104)
			(stroke
				(width 0.1524)
				(type default)
			)
			(layer "F.SilkS")
		)
		(fp_line
			(start -5.588 -5.150104)
			(end -5.588 -1.8542)
			(stroke
				(width 0.1524)
				(type default)
			)
			(layer "F.SilkS")
		)
		(fp_line
			(start 5.599938 5.150104)
			(end -5.599938 5.150104)
			(stroke
				(width 0.1)
				(type default)
			)
			(layer "F.Fab")
		)
		(fp_line
			(start 5.599938 -5.150104)
			(end 5.599938 5.150104)
			(stroke
				(width 0.1)
				(type default)
			)
			(layer "F.Fab")
		)
		(fp_line
			(start -5.599938 5.150104)
			(end -5.599938 -5.150104)
			(stroke
				(width 0.1)
				(type default)
			)
			(layer "F.Fab")
		)
		(fp_line
			(start -5.599938 -5.150104)
			(end 5.599938 -5.150104)
			(stroke
				(width 0.1)
				(type default)
			)
			(layer "F.Fab")
		)
		(pad "1" smd rect
			(at -4.338828 0 180)
			(size 3.302 3.302)
			(layers "F.Cu" "F.Mask" "F.Paste")
			(net "SW_P5V_AUX_SW")
		)
		(pad "2" smd rect
			(at 4.338828 0 180)
			(size 3.302 3.302)
			(layers "F.Cu" "F.Mask" "F.Paste")
			(net "P5V_AUX")
		)
	)
)
